(kicad_pcb
	(version 20260206)
	(generator "pcbnew")
	(generator_version "10.0")
	(general
		(thickness 1.6)
		(legacy_teardrops no)
	)
	(paper "A4")
	(title_block
		(title "Bryce Canyon_IOM_IOC_16318-2_OCP.brd")
		(comment 1 "Bryce Canyon / footprints 1240-1247 of 1605")
	)
	(layers
		(0 "F.Cu" signal "TOP")
		(4 "In1.Cu" signal "L2GND")
		(6 "In2.Cu" signal "L3")
		(8 "In3.Cu" signal "L4VCC")
		(10 "In4.Cu" signal "L5VCC")
		(12 "In5.Cu" signal "L6")
		(14 "In6.Cu" signal "L7GND")
		(2 "B.Cu" signal "BOTTOM")
		(9 "F.Adhes" user "F.Adhesive")
		(11 "B.Adhes" user "B.Adhesive")
		(13 "F.Paste" user "Package Geometry/Pastemask Top")
		(15 "B.Paste" user "Package Geometry/Pastemask Bottom")
		(5 "F.SilkS" user "Ref Des/Silkscreen Top")
		(7 "B.SilkS" user "Ref Des/Silkscreen Bottom")
		(1 "F.Mask" user "Board Geometry/Soldermask Top")
		(3 "B.Mask" user "Board Geometry/Soldermask Bottom")
		(17 "Dwgs.User" user "User.Drawings")
		(19 "Cmts.User" user "User.Comments")
		(21 "Eco1.User" user "User.Eco1")
		(23 "Eco2.User" user "User.Eco2")
		(25 "Edge.Cuts" user "Board Geometry/Outline")
		(27 "Margin" user)
		(31 "F.CrtYd" user "Package Geometry/Place Bound Top")
		(29 "B.CrtYd" user "Package Geometry/Place Bound Bottom")
		(35 "F.Fab" user "Ref Des/Assembly Top")
		(33 "B.Fab" user "Ref Des/Assembly Bottom")
	)
	(footprint ""
		(layer "B.Cu")
		(at 203.8604 -62.6872 90)
		(property "Reference" "C456"
			(at 0 0 90)
			(layer "B.SilkS")
			(hide yes)
			(effects
				(font
					(size 1.27 1.27)
				)
				(justify mirror)
			)
		)
		(property "Value" "SCD1U16V2KX-3GP"
			(at -1.1811 -2.7051 90)
			(unlocked yes)
			(layer "B.Fab")
			(hide yes)
			(effects
				(font
					(size 1.016 1.016)
					(thickness 0.1524)
				)
				(justify mirror)
			)
		)
		(property "Device Type" "C402H22"
			(at -1.1811 -4.2291 90)
			(unlocked yes)
			(layer "B.Fab")
			(hide yes)
			(effects
				(font
					(size 1.016 1.016)
					(thickness 0.1524)
				)
				(justify mirror)
			)
		)
		(duplicate_pad_numbers_are_jumpers no)
		(fp_rect
			(start 0.4318 0.9525)
			(end -0.4318 -0.9525)
			(stroke
				(width 0)
				(type default)
			)
			(fill no)
			(layer "B.CrtYd")
		)
		(fp_rect
			(start 0.4318 0.9525)
			(end -0.4318 -0.9525)
			(stroke
				(width 0)
				(type default)
			)
			(fill no)
			(layer "B.Fab")
		)
		(pad "1" smd custom
			(at 0 -0.4445 270)
			(size 0.1524 0.1524)
			(layers "B.Cu" "B.Mask" "B.Paste")
			(net "P1V8")
			(options
				(clearance outline)
				(anchor circle)
			)
			(primitives
				(gr_poly
					(pts
						(arc
							(start 0.3048 0.2032)
							(mid 0.275042 0.275042)
							(end 0.2032 0.3048)
						)
						(arc
							(start -0.2032 0.3048)
							(mid -0.275042 0.275042)
							(end -0.3048 0.2032)
						)
						(arc
							(start -0.3048 -0.2032)
							(mid -0.275042 -0.275042)
							(end -0.2032 -0.3048)
						)
						(arc
							(start 0.2032 -0.3048)
							(mid 0.275042 -0.275042)
							(end 0.3048 -0.2032)
						)
					)
					(width 0)
					(fill yes)
				)
			)
		)
		(pad "2" smd custom
			(at 0 0.4445 270)
			(size 0.1524 0.1524)
			(layers "B.Cu" "B.Mask" "B.Paste")
			(net "GND")
			(options
				(clearance outline)
				(anchor circle)
			)
			(primitives
				(gr_poly
					(pts
						(arc
							(start 0.3048 0.2032)
							(mid 0.275042 0.275042)
							(end 0.2032 0.3048)
						)
						(arc
							(start -0.2032 0.3048)
							(mid -0.275042 0.275042)
							(end -0.3048 0.2032)
						)
						(arc
							(start -0.3048 -0.2032)
							(mid -0.275042 -0.275042)
							(end -0.2032 -0.3048)
						)
						(arc
							(start 0.2032 -0.3048)
							(mid 0.275042 -0.275042)
							(end 0.3048 -0.2032)
						)
					)
					(width 0)
					(fill yes)
				)
			)
		)
	)
	(footprint ""
		(layer "B.Cu")
		(at 184.055766 -60.379356 90)
		(property "Reference" "C478"
			(at 0 0 90)
			(layer "B.SilkS")
			(hide yes)
			(effects
				(font
					(size 1.27 1.27)
				)
				(justify mirror)
			)
		)
		(property "Value" "SC1KP50V2KX-1GP"
			(at -1.1811 -2.7051 90)
			(unlocked yes)
			(layer "B.Fab")
			(hide yes)
			(effects
				(font
					(size 1.016 1.016)
					(thickness 0.1524)
				)
				(justify mirror)
			)
		)
		(property "Device Type" "C402H22"
			(at -1.1811 -4.2291 90)
			(unlocked yes)
			(layer "B.Fab")
			(hide yes)
			(effects
				(font
					(size 1.016 1.016)
					(thickness 0.1524)
				)
				(justify mirror)
			)
		)
		(duplicate_pad_numbers_are_jumpers no)
		(fp_rect
			(start 0.4318 0.9525)
			(end -0.4318 -0.9525)
			(stroke
				(width 0)
				(type default)
			)
			(fill no)
			(layer "B.CrtYd")
		)
		(fp_rect
			(start 0.4318 0.9525)
			(end -0.4318 -0.9525)
			(stroke
				(width 0)
				(type default)
			)
			(fill no)
			(layer "B.Fab")
		)
		(pad "1" smd custom
			(at 0 -0.4445 270)
			(size 0.1524 0.1524)
			(layers "B.Cu" "B.Mask" "B.Paste")
			(net "P1V8")
			(options
				(clearance outline)
				(anchor circle)
			)
			(primitives
				(gr_poly
					(pts
						(arc
							(start 0.3048 0.2032)
							(mid 0.275042 0.275042)
							(end 0.2032 0.3048)
						)
						(arc
							(start -0.2032 0.3048)
							(mid -0.275042 0.275042)
							(end -0.3048 0.2032)
						)
						(arc
							(start -0.3048 -0.2032)
							(mid -0.275042 -0.275042)
							(end -0.2032 -0.3048)
						)
						(arc
							(start 0.2032 -0.3048)
							(mid 0.275042 -0.275042)
							(end 0.3048 -0.2032)
						)
					)
					(width 0)
					(fill yes)
				)
			)
		)
		(pad "2" smd custom
			(at 0 0.4445 270)
			(size 0.1524 0.1524)
			(layers "B.Cu" "B.Mask" "B.Paste")
			(net "GND")
			(options
				(clearance outline)
				(anchor circle)
			)
			(primitives
				(gr_poly
					(pts
						(arc
							(start 0.3048 0.2032)
							(mid 0.275042 0.275042)
							(end 0.2032 0.3048)
						)
						(arc
							(start -0.2032 0.3048)
							(mid -0.275042 0.275042)
							(end -0.3048 0.2032)
						)
						(arc
							(start -0.3048 -0.2032)
							(mid -0.275042 -0.275042)
							(end -0.2032 -0.3048)
						)
						(arc
							(start 0.2032 -0.3048)
							(mid 0.275042 -0.275042)
							(end 0.3048 -0.2032)
						)
					)
					(width 0)
					(fill yes)
				)
			)
		)
	)
	(footprint ""
		(layer "B.Cu")
		(at 204.815948 -49.779682 -90)
		(property "Reference" "C339"
			(at 0 0 90)
			(layer "B.SilkS")
			(hide yes)
			(effects
				(font
					(size 1.27 1.27)
				)
				(justify mirror)
			)
		)
		(property "Value" "SC10U6D3V5KX-4GP"
			(at 0.0762 -6.1214 270)
			(unlocked yes)
			(layer "B.Fab")
			(hide yes)
			(effects
				(font
					(size 1.016 1.016)
					(thickness 0.1524)
				)
				(justify mirror)
			)
		)
		(property "Device Type" "C805H58"
			(at 0.0762 -8.1534 270)
			(unlocked yes)
			(layer "B.Fab")
			(hide yes)
			(effects
				(font
					(size 1.016 1.016)
					(thickness 0.1524)
				)
				(justify mirror)
			)
		)
		(duplicate_pad_numbers_are_jumpers no)
		(fp_line
			(start -0.635 0)
			(end 0.635 0)
			(stroke
				(width 0.508)
				(type default)
			)
			(layer "B.SilkS")
		)
		(fp_rect
			(start 0.9652 1.778)
			(end -0.9652 -1.778)
			(stroke
				(width 0)
				(type default)
			)
			(fill no)
			(layer "B.CrtYd")
		)
		(fp_poly
			(pts
				(xy 0.9652 -1.778) (xy -0.9652 -1.778) (xy -0.9652 1.778) (xy 0.9652 1.778)
			)
			(stroke
				(width 0)
				(type default)
			)
			(fill no)
			(layer "B.Fab")
		)
		(pad "1" smd rect
			(at 0 -0.9652 90)
			(size 1.397 1.143)
			(layers "B.Cu" "B.Mask" "B.Paste")
			(net "SHELL_PLL_VDD")
		)
		(pad "2" smd rect
			(at 0 0.9652 90)
			(size 1.397 1.143)
			(layers "B.Cu" "B.Mask" "B.Paste")
			(net "GND")
		)
	)
	(footprint ""
		(layer "B.Cu")
		(at 24.869902 -131.007358 180)
		(property "Reference" "R245"
			(at 0 0 0)
			(layer "B.SilkS")
			(hide yes)
			(effects
				(font
					(size 1.27 1.27)
				)
				(justify mirror)
			)
		)
		(property "Value" "120R2F-GP"
			(at -0.064008 -3.993896 180)
			(unlocked yes)
			(layer "B.Fab")
			(hide yes)
			(effects
				(font
					(size 1.016 1.016)
					(thickness 0.1524)
				)
				(justify mirror)
			)
		)
		(property "Device Type" "R402H16"
			(at -0.064008 -5.517896 180)
			(unlocked yes)
			(layer "B.Fab")
			(hide yes)
			(effects
				(font
					(size 1.016 1.016)
					(thickness 0.1524)
				)
				(justify mirror)
			)
		)
		(duplicate_pad_numbers_are_jumpers no)
		(fp_line
			(start 0.508 -0.9398)
			(end 0.508 0.9398)
			(stroke
				(width 0.1524)
				(type default)
			)
			(layer "B.SilkS")
		)
		(fp_line
			(start -0.508 -0.9398)
			(end 0.508 -0.9398)
			(stroke
				(width 0.1524)
				(type default)
			)
			(layer "B.SilkS")
		)
		(fp_rect
			(start 0.508 0.9398)
			(end -0.508 -0.9398)
			(stroke
				(width 0)
				(type default)
			)
			(fill no)
			(layer "B.CrtYd")
		)
		(fp_rect
			(start 0.508 0.9398)
			(end -0.508 -0.9398)
			(stroke
				(width 0)
				(type default)
			)
			(fill no)
			(layer "B.Fab")
		)
		(pad "1" smd custom
			(at 0 -0.4445)
			(size 0.1397 0.1397)
			(layers "B.Cu" "B.Mask" "B.Paste")
			(net "MEMA_5")
			(options
				(clearance outline)
				(anchor circle)
			)
			(primitives
				(gr_poly
					(pts
						(arc
							(start -0.1778 0.2794)
							(mid -0.249642 0.249642)
							(end -0.2794 0.1778)
						)
						(arc
							(start -0.2794 -0.1778)
							(mid -0.249642 -0.249642)
							(end -0.1778 -0.2794)
						)
						(arc
							(start 0.1778 -0.2794)
							(mid 0.249642 -0.249642)
							(end 0.2794 -0.1778)
						)
						(arc
							(start 0.2794 0.1778)
							(mid 0.249642 0.249642)
							(end 0.1778 0.2794)
						)
					)
					(width 0)
					(fill yes)
				)
			)
		)
		(pad "2" smd custom
			(at 0 0.4445)
			(size 0.1397 0.1397)
			(layers "B.Cu" "B.Mask" "B.Paste")
			(net "P1V2_STBY")
			(options
				(clearance outline)
				(anchor circle)
			)
			(primitives
				(gr_poly
					(pts
						(arc
							(start -0.1778 0.2794)
							(mid -0.249642 0.249642)
							(end -0.2794 0.1778)
						)
						(arc
							(start -0.2794 -0.1778)
							(mid -0.249642 -0.249642)
							(end -0.1778 -0.2794)
						)
						(arc
							(start 0.1778 -0.2794)
							(mid 0.249642 -0.249642)
							(end 0.2794 -0.1778)
						)
						(arc
							(start 0.2794 0.1778)
							(mid 0.249642 0.249642)
							(end 0.1778 0.2794)
						)
					)
					(width 0)
					(fill yes)
				)
			)
		)
	)
	(footprint ""
		(layer "B.Cu")
		(at 184.03824 -57.16524 90)
		(property "Reference" "C480"
			(at 0 0 90)
			(layer "B.SilkS")
			(hide yes)
			(effects
				(font
					(size 1.27 1.27)
				)
				(justify mirror)
			)
		)
		(property "Value" "SC1KP50V2KX-1GP"
			(at -1.1811 -2.7051 90)
			(unlocked yes)
			(layer "B.Fab")
			(hide yes)
			(effects
				(font
					(size 1.016 1.016)
					(thickness 0.1524)
				)
				(justify mirror)
			)
		)
		(property "Device Type" "C402H22"
			(at -1.1811 -4.2291 90)
			(unlocked yes)
			(layer "B.Fab")
			(hide yes)
			(effects
				(font
					(size 1.016 1.016)
					(thickness 0.1524)
				)
				(justify mirror)
			)
		)
		(duplicate_pad_numbers_are_jumpers no)
		(fp_rect
			(start 0.4318 0.9525)
			(end -0.4318 -0.9525)
			(stroke
				(width 0)
				(type default)
			)
			(fill no)
			(layer "B.CrtYd")
		)
		(fp_rect
			(start 0.4318 0.9525)
			(end -0.4318 -0.9525)
			(stroke
				(width 0)
				(type default)
			)
			(fill no)
			(layer "B.Fab")
		)
		(pad "1" smd custom
			(at 0 -0.4445 270)
			(size 0.1524 0.1524)
			(layers "B.Cu" "B.Mask" "B.Paste")
			(net "P1V8")
			(options
				(clearance outline)
				(anchor circle)
			)
			(primitives
				(gr_poly
					(pts
						(arc
							(start 0.3048 0.2032)
							(mid 0.275042 0.275042)
							(end 0.2032 0.3048)
						)
						(arc
							(start -0.2032 0.3048)
							(mid -0.275042 0.275042)
							(end -0.3048 0.2032)
						)
						(arc
							(start -0.3048 -0.2032)
							(mid -0.275042 -0.275042)
							(end -0.2032 -0.3048)
						)
						(arc
							(start 0.2032 -0.3048)
							(mid 0.275042 -0.275042)
							(end 0.3048 -0.2032)
						)
					)
					(width 0)
					(fill yes)
				)
			)
		)
		(pad "2" smd custom
			(at 0 0.4445 270)
			(size 0.1524 0.1524)
			(layers "B.Cu" "B.Mask" "B.Paste")
			(net "GND")
			(options
				(clearance outline)
				(anchor circle)
			)
			(primitives
				(gr_poly
					(pts
						(arc
							(start 0.3048 0.2032)
							(mid 0.275042 0.275042)
							(end 0.2032 0.3048)
						)
						(arc
							(start -0.2032 0.3048)
							(mid -0.275042 0.275042)
							(end -0.3048 0.2032)
						)
						(arc
							(start -0.3048 -0.2032)
							(mid -0.275042 -0.275042)
							(end -0.2032 -0.3048)
						)
						(arc
							(start 0.2032 -0.3048)
							(mid 0.275042 -0.275042)
							(end 0.3048 -0.2032)
						)
					)
					(width 0)
					(fill yes)
				)
			)
		)
	)
	(footprint ""
		(layer "B.Cu")
		(at 20.37715 -140.808202 -90)
		(property "Reference" "R206"
			(at 0 0 90)
			(layer "B.SilkS")
			(hide yes)
			(effects
				(font
					(size 1.27 1.27)
				)
				(justify mirror)
			)
		)
		(property "Value" "60D4R2F-GP"
			(at -0.064008 -3.993896 270)
			(unlocked yes)
			(layer "B.Fab")
			(hide yes)
			(effects
				(font
					(size 1.016 1.016)
					(thickness 0.1524)
				)
				(justify mirror)
			)
		)
		(property "Device Type" "R402H16"
			(at -0.064008 -5.517896 270)
			(unlocked yes)
			(layer "B.Fab")
			(hide yes)
			(effects
				(font
					(size 1.016 1.016)
					(thickness 0.1524)
				)
				(justify mirror)
			)
		)
		(duplicate_pad_numbers_are_jumpers no)
		(fp_line
			(start -0.508 -0.9398)
			(end 0.508 -0.9398)
			(stroke
				(width 0.1524)
				(type default)
			)
			(layer "B.SilkS")
		)
		(fp_line
			(start 0.508 -0.9398)
			(end 0.508 0.9398)
			(stroke
				(width 0.1524)
				(type default)
			)
			(layer "B.SilkS")
		)
		(fp_rect
			(start 0.508 0.9398)
			(end -0.508 -0.9398)
			(stroke
				(width 0)
				(type default)
			)
			(fill no)
			(layer "B.CrtYd")
		)
		(fp_rect
			(start 0.508 0.9398)
			(end -0.508 -0.9398)
			(stroke
				(width 0)
				(type default)
			)
			(fill no)
			(layer "B.Fab")
		)
		(pad "1" smd custom
			(at 0 -0.4445 90)
			(size 0.1397 0.1397)
			(layers "B.Cu" "B.Mask" "B.Paste")
			(net "MEMCK_N")
			(options
				(clearance outline)
				(anchor circle)
			)
			(primitives
				(gr_poly
					(pts
						(arc
							(start -0.1778 0.2794)
							(mid -0.249642 0.249642)
							(end -0.2794 0.1778)
						)
						(arc
							(start -0.2794 -0.1778)
							(mid -0.249642 -0.249642)
							(end -0.1778 -0.2794)
						)
						(arc
							(start 0.1778 -0.2794)
							(mid 0.249642 -0.249642)
							(end 0.2794 -0.1778)
						)
						(arc
							(start 0.2794 0.1778)
							(mid 0.249642 0.249642)
							(end 0.1778 0.2794)
						)
					)
					(width 0)
					(fill yes)
				)
			)
		)
		(pad "2" smd custom
			(at 0 0.4445 90)
			(size 0.1397 0.1397)
			(layers "B.Cu" "B.Mask" "B.Paste")
			(net "MEMCK_TER")
			(options
				(clearance outline)
				(anchor circle)
			)
			(primitives
				(gr_poly
					(pts
						(arc
							(start -0.1778 0.2794)
							(mid -0.249642 0.249642)
							(end -0.2794 0.1778)
						)
						(arc
							(start -0.2794 -0.1778)
							(mid -0.249642 -0.249642)
							(end -0.1778 -0.2794)
						)
						(arc
							(start 0.1778 -0.2794)
							(mid 0.249642 -0.249642)
							(end 0.2794 -0.1778)
						)
						(arc
							(start 0.2794 0.1778)
							(mid 0.249642 0.249642)
							(end 0.1778 0.2794)
						)
					)
					(width 0)
					(fill yes)
				)
			)
		)
	)
	(footprint ""
		(layer "B.Cu")
		(at 185.6486 -49.022 180)
		(property "Reference" "R767"
			(at 0 0 0)
			(layer "B.SilkS")
			(hide yes)
			(effects
				(font
					(size 1.27 1.27)
				)
				(justify mirror)
			)
		)
		(property "Value" "10KR2F-2-GP"
			(at -0.064008 -3.993896 180)
			(unlocked yes)
			(layer "B.Fab")
			(hide yes)
			(effects
				(font
					(size 1.016 1.016)
					(thickness 0.1524)
				)
				(justify mirror)
			)
		)
		(property "Device Type" "R402H16"
			(at -0.064008 -5.517896 180)
			(unlocked yes)
			(layer "B.Fab")
			(hide yes)
			(effects
				(font
					(size 1.016 1.016)
					(thickness 0.1524)
				)
				(justify mirror)
			)
		)
		(duplicate_pad_numbers_are_jumpers no)
		(fp_line
			(start 0.508 -0.9398)
			(end 0.508 0.9398)
			(stroke
				(width 0.1524)
				(type default)
			)
			(layer "B.SilkS")
		)
		(fp_line
			(start -0.508 -0.9398)
			(end 0.508 -0.9398)
			(stroke
				(width 0.1524)
				(type default)
			)
			(layer "B.SilkS")
		)
		(fp_rect
			(start 0.508 0.9398)
			(end -0.508 -0.9398)
			(stroke
				(width 0)
				(type default)
			)
			(fill no)
			(layer "B.CrtYd")
		)
		(fp_rect
			(start 0.508 0.9398)
			(end -0.508 -0.9398)
			(stroke
				(width 0)
				(type default)
			)
			(fill no)
			(layer "B.Fab")
		)
		(pad "1" smd custom
			(at 0 -0.4445)
			(size 0.1397 0.1397)
			(layers "B.Cu" "B.Mask" "B.Paste")
			(net "P1V8")
			(options
				(clearance outline)
				(anchor circle)
			)
			(primitives
				(gr_poly
					(pts
						(arc
							(start -0.1778 0.2794)
							(mid -0.249642 0.249642)
							(end -0.2794 0.1778)
						)
						(arc
							(start -0.2794 -0.1778)
							(mid -0.249642 -0.249642)
							(end -0.1778 -0.2794)
						)
						(arc
							(start 0.1778 -0.2794)
							(mid 0.249642 -0.249642)
							(end 0.2794 -0.1778)
						)
						(arc
							(start 0.2794 0.1778)
							(mid 0.249642 0.249642)
							(end 0.1778 0.2794)
						)
					)
					(width 0)
					(fill yes)
				)
			)
		)
		(pad "2" smd custom
			(at 0 0.4445)
			(size 0.1397 0.1397)
			(layers "B.Cu" "B.Mask" "B.Paste")
			(net "XM_ADDR_1")
			(options
				(clearance outline)
				(anchor circle)
			)
			(primitives
				(gr_poly
					(pts
						(arc
							(start -0.1778 0.2794)
							(mid -0.249642 0.249642)
							(end -0.2794 0.1778)
						)
						(arc
							(start -0.2794 -0.1778)
							(mid -0.249642 -0.249642)
							(end -0.1778 -0.2794)
						)
						(arc
							(start 0.1778 -0.2794)
							(mid 0.249642 -0.249642)
							(end 0.2794 -0.1778)
						)
						(arc
							(start 0.2794 0.1778)
							(mid 0.249642 0.249642)
							(end 0.1778 0.2794)
						)
					)
					(width 0)
					(fill yes)
				)
			)
		)
	)
	(footprint ""
		(layer "B.Cu")
		(at 201.110342 -46.308772 90)
		(property "Reference" "R680"
			(at 0 0 90)
			(layer "B.SilkS")
			(hide yes)
			(effects
				(font
					(size 1.27 1.27)
				)
				(justify mirror)
			)
		)
		(property "Value" "10R2F-L-GP"
			(at -0.064008 -3.993896 90)
			(unlocked yes)
			(layer "B.Fab")
			(hide yes)
			(effects
				(font
					(size 1.016 1.016)
					(thickness 0.1524)
				)
				(justify mirror)
			)
		)
		(property "Device Type" "R402H14"
			(at -0.064008 -5.517896 90)
			(unlocked yes)
			(layer "B.Fab")
			(hide yes)
			(effects
				(font
					(size 1.016 1.016)
					(thickness 0.1524)
				)
				(justify mirror)
			)
		)
		(duplicate_pad_numbers_are_jumpers no)
		(fp_line
			(start 0.508 -0.9398)
			(end 0.508 0.9398)
			(stroke
				(width 0.1524)
				(type default)
			)
			(layer "B.SilkS")
		)
		(fp_line
			(start -0.508 -0.9398)
			(end 0.508 -0.9398)
			(stroke
				(width 0.1524)
				(type default)
			)
			(layer "B.SilkS")
		)
		(fp_rect
			(start 0.508 0.9398)
			(end -0.508 -0.9398)
			(stroke
				(width 0)
				(type default)
			)
			(fill no)
			(layer "B.CrtYd")
		)
		(fp_rect
			(start 0.508 0.9398)
			(end -0.508 -0.9398)
			(stroke
				(width 0)
				(type default)
			)
			(fill no)
			(layer "B.Fab")
		)
		(pad "1" smd custom
			(at 0 -0.4445 270)
			(size 0.1397 0.1397)
			(layers "B.Cu" "B.Mask" "B.Paste")
			(net "P1V8")
			(options
				(clearance outline)
				(anchor circle)
			)
			(primitives
				(gr_poly
					(pts
						(arc
							(start -0.1778 0.2794)
							(mid -0.249642 0.249642)
							(end -0.2794 0.1778)
						)
						(arc
							(start -0.2794 -0.1778)
							(mid -0.249642 -0.249642)
							(end -0.1778 -0.2794)
						)
						(arc
							(start 0.1778 -0.2794)
							(mid 0.249642 -0.249642)
							(end 0.2794 -0.1778)
						)
						(arc
							(start 0.2794 0.1778)
							(mid 0.249642 0.249642)
							(end 0.1778 0.2794)
						)
					)
					(width 0)
					(fill yes)
				)
			)
		)
		(pad "2" smd custom
			(at 0 0.4445 270)
			(size 0.1397 0.1397)
			(layers "B.Cu" "B.Mask" "B.Paste")
			(net "SYS_PLL_VDD")
			(options
				(clearance outline)
				(anchor circle)
			)
			(primitives
				(gr_poly
					(pts
						(arc
							(start -0.1778 0.2794)
							(mid -0.249642 0.249642)
							(end -0.2794 0.1778)
						)
						(arc
							(start -0.2794 -0.1778)
							(mid -0.249642 -0.249642)
							(end -0.1778 -0.2794)
						)
						(arc
							(start 0.1778 -0.2794)
							(mid 0.249642 -0.249642)
							(end 0.2794 -0.1778)
						)
						(arc
							(start 0.2794 0.1778)
							(mid 0.249642 0.249642)
							(end 0.1778 0.2794)
						)
					)
					(width 0)
					(fill yes)
				)
			)
		)
	)
)
